# BASEBOARD_FAB2 (Tioga Pass) — schematic netlist excerpt (pin names and nets, part order shuffled) for the footprints in the layout excerpt that follows; sources: Cadence DE-HDL packaged netlist, KiCad conversion of Wiwynn_Tioga_Pass_MB.brd

R8F24  RES  4.75K 1% CHIP  pkg 0402  page 157 : A = P3V3_STBY ; B = FP_NMI_BTN_N
R6P19  RES  0.0 5% CHIP  pkg 0402  page 203 : A = VR_PVCCIN_CPU0_PH3_VCIN ; B = P5V_STBY
R3N2  RES  4.75K 1% EMPTY  pkg 0402  page 125 : A = P3V3_STBY ; B = FM_FLASH_DESC_OVERRIDE

(kicad_pcb
	(version 20260206)
	(generator "pcbnew")
	(generator_version "10.0")
	(general
		(thickness 1.6)
		(legacy_teardrops no)
	)
	(paper "A4")
	(title_block
		(title "Wiwynn_Tioga_Pass_MB.brd")
		(comment 1 "Tioga Pass / footprints 4463-4465 of 4770")
	)
	(layers
		(0 "F.Cu" signal "TOP")
		(4 "In1.Cu" signal "L2GND")
		(6 "In2.Cu" signal "L3")
		(8 "In3.Cu" signal "L4GND")
		(10 "In4.Cu" signal "L5")
		(12 "In5.Cu" signal "L6GND")
		(14 "In6.Cu" signal "L7VCC")
		(16 "In7.Cu" signal "L8VCC")
		(18 "In8.Cu" signal "L9GND")
		(20 "In9.Cu" signal "L10")
		(22 "In10.Cu" signal "L11GND")
		(24 "In11.Cu" signal "L12")
		(26 "In12.Cu" signal "L13GND")
		(2 "B.Cu" signal "BOTTOM")
		(9 "F.Adhes" user "F.Adhesive")
		(11 "B.Adhes" user "B.Adhesive")
		(13 "F.Paste" user "Package Geometry/Pastemask Top")
		(15 "B.Paste" user "Package Geometry/Pastemask Bottom")
		(5 "F.SilkS" user "Ref Des/Silkscreen Top")
		(7 "B.SilkS" user "Ref Des/Silkscreen Bottom")
		(1 "F.Mask" user "Board Geometry/Soldermask Top")
		(3 "B.Mask" user "Board Geometry/Soldermask Bottom")
		(17 "Dwgs.User" user "User.Drawings")
		(19 "Cmts.User" user "User.Comments")
		(21 "Eco1.User" user "User.Eco1")
		(23 "Eco2.User" user "User.Eco2")
		(25 "Edge.Cuts" user "Board Geometry/Outline")
		(27 "Margin" user)
		(31 "F.CrtYd" user "Package Geometry/Place Bound Top")
		(29 "B.CrtYd" user "Package Geometry/Place Bound Bottom")
		(35 "F.Fab" user "Ref Des/Assembly Top")
		(33 "B.Fab" user "Ref Des/Assembly Bottom")
	)
	(footprint ""
		(layer "B.Cu")
		(at 407.3652 -13.0683 180)
		(property "Reference" "R8F24"
			(at 0 0 0)
			(layer "B.SilkS")
			(hide yes)
			(effects
				(font
					(size 1.27 1.27)
				)
				(justify mirror)
			)
		)
		(property "Value" ""
			(at 0 0 0)
			(layer "B.Fab")
			(effects
				(font
					(size 1.27 1.27)
				)
				(justify mirror)
			)
		)
		(duplicate_pad_numbers_are_jumpers no)
		(fp_poly
			(pts
				(xy 0.2794 -0.1016) (xy -0.2794 -0.1016) (xy -0.2794 0.9906) (xy 0.2794 0.9906)
			)
			(stroke
				(width 0)
				(type default)
			)
			(fill no)
			(layer "B.CrtYd")
		)
		(fp_line
			(start 0.2794 0.9906)
			(end -0.2794 0.9906)
			(stroke
				(width 0.1)
				(type default)
			)
			(layer "B.Fab")
		)
		(fp_line
			(start 0.2794 -0.1016)
			(end 0.2794 0.9906)
			(stroke
				(width 0.1)
				(type default)
			)
			(layer "B.Fab")
		)
		(fp_line
			(start -0.2794 0.9906)
			(end -0.2794 -0.1016)
			(stroke
				(width 0.1)
				(type default)
			)
			(layer "B.Fab")
		)
		(fp_line
			(start -0.2794 -0.1016)
			(end 0.2794 -0.1016)
			(stroke
				(width 0.1)
				(type default)
			)
			(layer "B.Fab")
		)
		(pad "1" smd rect
			(at 0 0)
			(size 0.508 0.508)
			(layers "B.Cu" "B.Mask" "B.Paste")
			(net "P3V3_STBY")
		)
		(pad "2" smd rect
			(at 0 0.889)
			(size 0.508 0.508)
			(layers "B.Cu" "B.Mask" "B.Paste")
			(net "FP_NMI_BTN_N")
		)
		(zone
			(layer "B.Cu")
			(hatch none 0.5)
			(connect_pads
				(clearance 0)
			)
			(min_thickness 0.25)
			(keepout
				(tracks not_allowed)
				(vias allowed)
				(pads allowed)
				(copperpour not_allowed)
				(footprints allowed)
			)
			(placement
				(enabled no)
				(sheetname "")
			)
			(fill
				(thermal_gap 0.5)
				(thermal_bridge_width 0.5)
				(island_removal_mode 0)
			)
			(polygon
				(pts
					(xy 407.1112 -13.7033) (xy 407.6192 -13.7033) (xy 407.6192 -13.3223) (xy 407.1112 -13.3223)
				)
			)
		)
		(zone
			(layer "B.Cu")
			(hatch none 0.5)
			(connect_pads
				(clearance 0)
			)
			(min_thickness 0.25)
			(keepout
				(tracks allowed)
				(vias not_allowed)
				(pads allowed)
				(copperpour not_allowed)
				(footprints allowed)
			)
			(placement
				(enabled no)
				(sheetname "")
			)
			(fill
				(thermal_gap 0.5)
				(thermal_bridge_width 0.5)
				(island_removal_mode 0)
			)
			(polygon
				(pts
					(xy 407.1112 -13.3223) (xy 407.6192 -13.3223) (xy 407.6192 -13.7033) (xy 407.1112 -13.7033)
				)
			)
		)
	)
	(footprint ""
		(layer "B.Cu")
		(at 197.239128 -70.787006 90)
		(property "Reference" "R6P19"
			(at 0 0 90)
			(layer "B.SilkS")
			(hide yes)
			(effects
				(font
					(size 1.27 1.27)
				)
				(justify mirror)
			)
		)
		(property "Value" ""
			(at 0 0 90)
			(layer "B.Fab")
			(effects
				(font
					(size 1.27 1.27)
				)
				(justify mirror)
			)
		)
		(duplicate_pad_numbers_are_jumpers no)
		(fp_rect
			(start 0.2794 -0.1016)
			(end -0.2794 0.9906)
			(stroke
				(width 0)
				(type default)
			)
			(fill no)
			(layer "B.CrtYd")
		)
		(fp_line
			(start 0.2794 -0.1016)
			(end 0.2794 0.9906)
			(stroke
				(width 0.1)
				(type default)
			)
			(layer "B.Fab")
		)
		(fp_line
			(start -0.2794 -0.1016)
			(end 0.2794 -0.1016)
			(stroke
				(width 0.1)
				(type default)
			)
			(layer "B.Fab")
		)
		(fp_line
			(start 0.2794 0.9906)
			(end -0.2794 0.9906)
			(stroke
				(width 0.1)
				(type default)
			)
			(layer "B.Fab")
		)
		(fp_line
			(start -0.2794 0.9906)
			(end -0.2794 -0.1016)
			(stroke
				(width 0.1)
				(type default)
			)
			(layer "B.Fab")
		)
		(pad "1" smd rect
			(at 0 0 270)
			(size 0.508 0.508)
			(layers "B.Cu" "B.Mask" "B.Paste")
			(net "VR_PVCCIN_CPU0_PH3_VCIN")
		)
		(pad "2" smd rect
			(at 0 0.889 270)
			(size 0.508 0.508)
			(layers "B.Cu" "B.Mask" "B.Paste")
			(net "P5V_STBY")
		)
		(zone
			(layer "B.Cu")
			(hatch none 0.5)
			(connect_pads
				(clearance 0)
			)
			(min_thickness 0.25)
			(keepout
				(tracks not_allowed)
				(vias allowed)
				(pads allowed)
				(copperpour not_allowed)
				(footprints allowed)
			)
			(placement
				(enabled no)
				(sheetname "")
			)
			(fill
				(thermal_gap 0.5)
				(thermal_bridge_width 0.5)
				(island_removal_mode 0)
			)
			(polygon
				(pts
					(xy 197.493128 -71.041006) (xy 197.493128 -70.533006) (xy 197.874128 -70.533006) (xy 197.874128 -71.041006)
				)
			)
		)
		(zone
			(layer "B.Cu")
			(hatch none 0.5)
			(connect_pads
				(clearance 0)
			)
			(min_thickness 0.25)
			(keepout
				(tracks allowed)
				(vias not_allowed)
				(pads allowed)
				(copperpour not_allowed)
				(footprints allowed)
			)
			(placement
				(enabled no)
				(sheetname "")
			)
			(fill
				(thermal_gap 0.5)
				(thermal_bridge_width 0.5)
				(island_removal_mode 0)
			)
			(polygon
				(pts
					(xy 197.493128 -71.041006) (xy 197.493128 -70.533006) (xy 197.874128 -70.533006) (xy 197.874128 -71.041006)
				)
			)
		)
	)
	(footprint ""
		(layer "B.Cu")
		(at 382.473708 -104.314244 -90)
		(property "Reference" "R3N2"
			(at 0 0 90)
			(layer "B.SilkS")
			(hide yes)
			(effects
				(font
					(size 1.27 1.27)
				)
				(justify mirror)
			)
		)
		(property "Value" ""
			(at 0 0 90)
			(layer "B.Fab")
			(effects
				(font
					(size 1.27 1.27)
				)
				(justify mirror)
			)
		)
		(duplicate_pad_numbers_are_jumpers no)
		(fp_poly
			(pts
				(xy 0.2794 -0.1016) (xy -0.2794 -0.1016) (xy -0.2794 0.9906) (xy 0.2794 0.9906)
			)
			(stroke
				(width 0)
				(type default)
			)
			(fill no)
			(layer "B.CrtYd")
		)
		(fp_line
			(start -0.2794 0.9906)
			(end -0.2794 -0.1016)
			(stroke
				(width 0.1)
				(type default)
			)
			(layer "B.Fab")
		)
		(fp_line
			(start 0.2794 0.9906)
			(end -0.2794 0.9906)
			(stroke
				(width 0.1)
				(type default)
			)
			(layer "B.Fab")
		)
		(fp_line
			(start -0.2794 -0.1016)
			(end 0.2794 -0.1016)
			(stroke
				(width 0.1)
				(type default)
			)
			(layer "B.Fab")
		)
		(fp_line
			(start 0.2794 -0.1016)
			(end 0.2794 0.9906)
			(stroke
				(width 0.1)
				(type default)
			)
			(layer "B.Fab")
		)
		(pad "1" smd rect
			(at 0 0 90)
			(size 0.508 0.508)
			(layers "B.Cu" "B.Mask" "B.Paste")
			(net "P3V3_STBY")
		)
		(pad "2" smd rect
			(at 0 0.889 90)
			(size 0.508 0.508)
			(layers "B.Cu" "B.Mask" "B.Paste")
			(net "FM_FLASH_DESC_OVERRIDE")
		)
		(zone
			(layer "B.Cu")
			(hatch none 0.5)
			(connect_pads
				(clearance 0)
			)
			(min_thickness 0.25)
			(keepout
				(tracks not_allowed)
				(vias allowed)
				(pads allowed)
				(copperpour not_allowed)
				(footprints allowed)
			)
			(placement
				(enabled no)
				(sheetname "")
			)
			(fill
				(thermal_gap 0.5)
				(thermal_bridge_width 0.5)
				(island_removal_mode 0)
			)
			(polygon
				(pts
					(xy 381.838708 -104.060244) (xy 381.838708 -104.568244) (xy 382.219708 -104.568244) (xy 382.219708 -104.060244)
				)
			)
		)
		(zone
			(layer "B.Cu")
			(hatch none 0.5)
			(connect_pads
				(clearance 0)
			)
			(min_thickness 0.25)
			(keepout
				(tracks allowed)
				(vias not_allowed)
				(pads allowed)
				(copperpour not_allowed)
				(footprints allowed)
			)
			(placement
				(enabled no)
				(sheetname "")
			)
			(fill
				(thermal_gap 0.5)
				(thermal_bridge_width 0.5)
				(island_removal_mode 0)
			)
			(polygon
				(pts
					(xy 382.219708 -104.060244) (xy 382.219708 -104.568244) (xy 381.838708 -104.568244) (xy 381.838708 -104.060244)
				)
			)
		)
	)
)
